(kicad_pcb
	(version 20241229)
	(generator "pcbnew")
	(generator_version "9.0")
	(general
		(thickness 1.6642)
		(legacy_teardrops no)
	)
	(paper "A3")
	(title_block
		(title "PolarFire SoM")
		(date "2025-07-22")
		(rev "1.1.4")
		(company "Antmicro Ltd")
		(comment 1 "www.antmicro.com")
		(comment 9 "footprints 5-7 of 470")
	)
	(layers
		(0 "F.Cu" mixed)
		(4 "In1.Cu" power)
		(6 "In2.Cu" signal)
		(8 "In3.Cu" power)
		(10 "In4.Cu" signal)
		(12 "In5.Cu" power)
		(14 "In6.Cu" power)
		(16 "In7.Cu" signal)
		(18 "In8.Cu" power)
		(20 "In9.Cu" signal)
		(22 "In10.Cu" power)
		(24 "In11.Cu" signal)
		(26 "In12.Cu" signal)
		(2 "B.Cu" mixed)
		(9 "F.Adhes" user "F.Adhesive")
		(11 "B.Adhes" user "B.Adhesive")
		(13 "F.Paste" user)
		(15 "B.Paste" user)
		(5 "F.SilkS" user "F.Silkscreen")
		(7 "B.SilkS" user "B.Silkscreen")
		(1 "F.Mask" user)
		(3 "B.Mask" user)
		(17 "Dwgs.User" user "User.Drawings")
		(19 "Cmts.User" user "User.Comments")
		(21 "Eco1.User" user "User.Eco1")
		(23 "Eco2.User" user "User.Eco2")
		(25 "Edge.Cuts" user)
		(27 "Margin" user)
		(31 "F.CrtYd" user "F.Courtyard")
		(29 "B.CrtYd" user "B.Courtyard")
		(35 "F.Fab" user)
		(33 "B.Fab" user)
	)
	(footprint "antmicro-footprints:C_Pol_EIA-B"
		(layer "F.Cu")
		(at 210.189 140.95 -90)
		(property "Reference" "C65"
			(at -2.15 1.789 90)
			(layer "F.SilkS")
			(effects
				(font
					(size 0.7 0.7)
					(thickness 0.15)
				)
				(justify right bottom)
			)
		)
		(property "Value" "C_Pol_330u_6.3V_KEMET-T520-B"
			(at 0 2.85 90)
			(layer "F.Fab")
			(hide yes)
			(effects
				(font
					(size 0.7 0.7)
					(thickness 0.15)
				)
				(justify right bottom)
			)
		)
		(property "Datasheet" "https://www.kemet.com/en/us/capacitors/product/T520B337M006ATE040.html"
			(at 0 0 90)
			(layer "F.Fab")
			(hide yes)
			(effects
				(font
					(size 1.27 1.27)
					(thickness 0.15)
				)
			)
		)
		(property "Description" "Tantalum Polymer Capacitor, KO-CAP®, 330 µF, ± 20%, 6.3 V, B, 0.04 ohm, 1411 [3528 Metric]"
			(at 0 0 90)
			(layer "F.Fab")
			(hide yes)
			(effects
				(font
					(size 1.27 1.27)
					(thickness 0.15)
				)
			)
		)
		(property "Author" "Antmicro"
			(at 69.239 351.139 0)
			(layer "F.Fab")
			(hide yes)
			(effects
				(font
					(size 1 1)
					(thickness 0.15)
				)
			)
		)
		(property "Capacitance" "330u"
			(at 69.239 351.139 0)
			(layer "F.Fab")
			(hide yes)
			(effects
				(font
					(size 1 1)
					(thickness 0.15)
				)
			)
		)
		(property "Dielectric" "template_dielectric"
			(at 69.239 351.139 0)
			(layer "F.Fab")
			(hide yes)
			(effects
				(font
					(size 1 1)
					(thickness 0.15)
				)
			)
		)
		(property "License" "Apache-2.0"
			(at 69.239 351.139 0)
			(layer "F.Fab")
			(hide yes)
			(effects
				(font
					(size 1 1)
					(thickness 0.15)
				)
			)
		)
		(property "MPN" "T520B337M006ATE040"
			(at 69.239 351.139 0)
			(layer "F.Fab")
			(hide yes)
			(effects
				(font
					(size 1 1)
					(thickness 0.15)
				)
			)
		)
		(property "Manufacturer" "KEMET"
			(at 69.239 351.139 0)
			(layer "F.Fab")
			(hide yes)
			(effects
				(font
					(size 1 1)
					(thickness 0.15)
				)
			)
		)
		(property "Public" ""
			(at 69.239 351.139 0)
			(layer "F.Fab")
			(hide yes)
			(effects
				(font
					(size 1 1)
					(thickness 0.15)
				)
			)
		)
		(property "Val" "330u"
			(at 69.239 351.139 0)
			(layer "F.Fab")
			(hide yes)
			(effects
				(font
					(size 1 1)
					(thickness 0.15)
				)
			)
		)
		(property "Voltage" "6.3V"
			(at 69.239 351.139 0)
			(layer "F.Fab")
			(hide yes)
			(effects
				(font
					(size 1 1)
					(thickness 0.15)
				)
			)
		)
		(sheetname "/FPGA Supply/")
		(sheetfile "fpga-supply.kicad_sch")
		(attr smd)
		(fp_line
			(start 1.8 1.6)
			(end -1.8 1.6)
			(stroke
				(width 0.15)
				(type solid)
			)
			(layer "F.SilkS")
		)
		(fp_line
			(start -1.8 1.3)
			(end -1.8 1.6)
			(stroke
				(width 0.15)
				(type solid)
			)
			(layer "F.SilkS")
		)
		(fp_line
			(start 1.8 1.3)
			(end 1.8 1.6)
			(stroke
				(width 0.15)
				(type solid)
			)
			(layer "F.SilkS")
		)
		(fp_line
			(start -1.8 -1.3)
			(end -1.8 -1.6)
			(stroke
				(width 0.15)
				(type solid)
			)
			(layer "F.SilkS")
		)
		(fp_line
			(start 1.8 -1.3)
			(end 1.8 -1.6)
			(stroke
				(width 0.15)
				(type solid)
			)
			(layer "F.SilkS")
		)
		(fp_line
			(start -2.325 -1.475)
			(end -2.325 -1.878)
			(stroke
				(width 0.15)
				(type solid)
			)
			(layer "F.SilkS")
		)
		(fp_line
			(start -1.8 -1.6)
			(end 1.8 -1.6)
			(stroke
				(width 0.15)
				(type solid)
			)
			(layer "F.SilkS")
		)
		(fp_line
			(start -2.521 -1.676)
			(end -2.123 -1.676)
			(stroke
				(width 0.15)
				(type solid)
			)
			(layer "F.SilkS")
		)
		(fp_line
			(start 1.96 1.75)
			(end -1.97 1.75)
			(stroke
				(width 0.05)
				(type solid)
			)
			(layer "F.CrtYd")
		)
		(fp_line
			(start -1.97 1.35)
			(end -1.97 1.75)
			(stroke
				(width 0.05)
				(type solid)
			)
			(layer "F.CrtYd")
		)
		(fp_line
			(start -1.97 1.35)
			(end -2.41 1.35)
			(stroke
				(width 0.05)
				(type solid)
			)
			(layer "F.CrtYd")
		)
		(fp_line
			(start 1.96 1.35)
			(end 1.96 1.75)
			(stroke
				(width 0.05)
				(type solid)
			)
			(layer "F.CrtYd")
		)
		(fp_line
			(start 2.4 1.35)
			(end 1.96 1.35)
			(stroke
				(width 0.05)
				(type solid)
			)
			(layer "F.CrtYd")
		)
		(fp_line
			(start -2.411 -1.35)
			(end -2.41 1.35)
			(stroke
				(width 0.05)
				(type solid)
			)
			(layer "F.CrtYd")
		)
		(fp_line
			(start -1.97 -1.35)
			(end -2.41 -1.35)
			(stroke
				(width 0.05)
				(type solid)
			)
			(layer "F.CrtYd")
		)
		(fp_line
			(start 2.399 -1.35)
			(end 2.4 1.35)
			(stroke
				(width 0.05)
				(type solid)
			)
			(layer "F.CrtYd")
		)
		(fp_line
			(start 2.399 -1.35)
			(end 1.959 -1.35)
			(stroke
				(width 0.05)
				(type solid)
			)
			(layer "F.CrtYd")
		)
		(fp_line
			(start -1.97 -1.75)
			(end -1.97 -1.35)
			(stroke
				(width 0.05)
				(type solid)
			)
			(layer "F.CrtYd")
		)
		(fp_line
			(start 1.959 -1.75)
			(end 1.959 -1.35)
			(stroke
				(width 0.05)
				(type solid)
			)
			(layer "F.CrtYd")
		)
		(fp_line
			(start 1.959 -1.75)
			(end -1.97 -1.75)
			(stroke
				(width 0.05)
				(type solid)
			)
			(layer "F.CrtYd")
		)
		(fp_line
			(start -1.7 1.324)
			(end -1.551 1.475)
			(stroke
				(width 0.15)
				(type solid)
			)
			(layer "F.Fab")
		)
		(fp_rect
			(start -1.72 -1.5)
			(end 1.719 1.499)
			(stroke
				(width 0.15)
				(type solid)
			)
			(fill no)
			(layer "F.Fab")
		)
		(fp_text user "${REFERENCE}"
			(at -2.665 4.45 270)
			(layer "F.Fab")
			(effects
				(font
					(size 0.7 0.7)
					(thickness 0.15)
				)
				(justify left bottom)
			)
		)
		(fp_text user "License: Apache-2.0"
			(at -2.665 5.65 270)
			(layer "F.Fab")
			(effects
				(font
					(size 0.7 0.7)
					(thickness 0.15)
				)
				(justify left bottom)
			)
		)
		(fp_text user "Author: Antmicro"
			(at -2.665 6.85 270)
			(layer "F.Fab")
			(effects
				(font
					(size 0.7 0.7)
					(thickness 0.15)
				)
				(justify left bottom)
			)
		)
		(pad "1" smd roundrect
			(at -1.551 0 270)
			(size 1.2 2.2)
			(layers "F.Cu" "F.Mask" "F.Paste")
			(roundrect_rratio 0.1)
			(net 47 "+1V05")
			(pintype "passive")
		)
		(pad "2" smd roundrect
			(at 1.55 0 270)
			(size 1.2 2.2)
			(layers "F.Cu" "F.Mask" "F.Paste")
			(roundrect_rratio 0.1)
			(net 417 "GND")
			(pintype "passive")
		)
	)
	(footprint "antmicro-footprints:TP_SMD_0.75mm"
		(layer "F.Cu")
		(at 206.3 142.85)
		(property "Reference" "TP12"
			(at 0 -0.6 0)
			(layer "F.SilkS")
			(hide yes)
			(effects
				(font
					(size 0.7 0.7)
					(thickness 0.15)
				)
				(justify left bottom)
			)
		)
		(property "Value" "TP_0.75mm_SMD"
			(at 0 1.2 0)
			(layer "F.Fab")
			(hide yes)
			(effects
				(font
					(size 0.7 0.7)
					(thickness 0.15)
				)
				(justify left bottom)
			)
		)
		(property "Description" "SMT test point"
			(at 0 0 0)
			(layer "F.Fab")
			(hide yes)
			(effects
				(font
					(size 1.27 1.27)
					(thickness 0.15)
				)
			)
		)
		(property "Author" "Antmicro"
			(at 0 0 0)
			(layer "F.Fab")
			(hide yes)
			(effects
				(font
					(size 1 1)
					(thickness 0.15)
				)
			)
		)
		(property "License" "Apache-2.0"
			(at 0 0 0)
			(layer "F.Fab")
			(hide yes)
			(effects
				(font
					(size 1 1)
					(thickness 0.15)
				)
			)
		)
		(property "MPN" ""
			(at 0 0 0)
			(layer "F.Fab")
			(hide yes)
			(effects
				(font
					(size 1 1)
					(thickness 0.15)
				)
			)
		)
		(property "Manufacturer" ""
			(at 0 0 0)
			(layer "F.Fab")
			(hide yes)
			(effects
				(font
					(size 1 1)
					(thickness 0.15)
				)
			)
		)
		(property "Public" "False"
			(at 0 0 0)
			(layer "F.Fab")
			(hide yes)
			(effects
				(font
					(size 1 1)
					(thickness 0.15)
				)
			)
		)
		(sheetname "/MIPI CrossLink/")
		(sheetfile "crosslink.kicad_sch")
		(attr exclude_from_pos_files exclude_from_bom)
		(fp_circle
			(center 0 0)
			(end 0.475 0)
			(stroke
				(width 0.05)
				(type default)
			)
			(fill no)
			(layer "F.CrtYd")
		)
		(fp_text user "License: Apache-2.0"
			(at -0.4 5.101 0)
			(layer "F.Fab")
			(effects
				(font
					(size 0.7 0.7)
					(thickness 0.15)
				)
				(justify left bottom)
			)
		)
		(fp_text user "${REFERENCE}"
			(at -0.4 2.7 0)
			(layer "F.Fab")
			(effects
				(font
					(size 0.7 0.7)
					(thickness 0.15)
				)
				(justify left bottom)
			)
		)
		(fp_text user "Author: Antmicro"
			(at -0.4 3.901 0)
			(layer "F.Fab")
			(effects
				(font
					(size 0.7 0.7)
					(thickness 0.15)
				)
				(justify left bottom)
			)
		)
		(pad "1" smd circle
			(at 0 0)
			(size 0.75 0.75)
			(layers "F.Cu" "F.Mask")
			(net 332 "Net-(U16-PB49{slash}PMU_WKUPN{slash}CDONE)")
			(pinfunction "1")
			(pintype "passive")
		)
	)
	(footprint "antmicro-footprints:TP_SMD_0.75mm"
		(layer "F.Cu")
		(at 227.2 144.64)
		(property "Reference" "TP31"
			(at 10.37 1.12 0)
			(layer "F.SilkS")
			(hide yes)
			(effects
				(font
					(size 0.7 0.7)
					(thickness 0.15)
				)
				(justify left bottom)
			)
		)
		(property "Value" "TP_0.75mm_SMD"
			(at 0 1.2 0)
			(layer "F.Fab")
			(hide yes)
			(effects
				(font
					(size 0.7 0.7)
					(thickness 0.15)
				)
				(justify left bottom)
			)
		)
		(property "Description" "SMT test point"
			(at 0 0 0)
			(layer "F.Fab")
			(hide yes)
			(effects
				(font
					(size 1.27 1.27)
					(thickness 0.15)
				)
			)
		)
		(property "Author" "Antmicro"
			(at 0 0 0)
			(layer "F.Fab")
			(hide yes)
			(effects
				(font
					(size 1 1)
					(thickness 0.15)
				)
			)
		)
		(property "License" "Apache-2.0"
			(at 0 0 0)
			(layer "F.Fab")
			(hide yes)
			(effects
				(font
					(size 1 1)
					(thickness 0.15)
				)
			)
		)
		(property "MPN" ""
			(at 0 0 0)
			(layer "F.Fab")
			(hide yes)
			(effects
				(font
					(size 1 1)
					(thickness 0.15)
				)
			)
		)
		(property "Manufacturer" ""
			(at 0 0 0)
			(layer "F.Fab")
			(hide yes)
			(effects
				(font
					(size 1 1)
					(thickness 0.15)
				)
			)
		)
		(property "Public" "False"
			(at 0 0 0)
			(layer "F.Fab")
			(hide yes)
			(effects
				(font
					(size 1 1)
					(thickness 0.15)
				)
			)
		)
		(sheetname "/WiFi_Bluetooth/")
		(sheetfile "wifi_bt.kicad_sch")
		(attr exclude_from_pos_files exclude_from_bom)
		(fp_circle
			(center 0 0)
			(end 0.475 0)
			(stroke
				(width 0.05)
				(type default)
			)
			(fill no)
			(layer "F.CrtYd")
		)
		(fp_text user "Author: Antmicro"
			(at -0.4 3.901 0)
			(layer "F.Fab")
			(effects
				(font
					(size 0.7 0.7)
					(thickness 0.15)
				)
				(justify left bottom)
			)
		)
		(fp_text user "License: Apache-2.0"
			(at -0.4 5.101 0)
			(layer "F.Fab")
			(effects
				(font
					(size 0.7 0.7)
					(thickness 0.15)
				)
				(justify left bottom)
			)
		)
		(fp_text user "${REFERENCE}"
			(at -0.4 2.7 0)
			(layer "F.Fab")
			(effects
				(font
					(size 0.7 0.7)
					(thickness 0.15)
				)
				(justify left bottom)
			)
		)
		(pad "1" smd circle
			(at 0 0)
			(size 0.75 0.75)
			(layers "F.Cu" "F.Mask")
			(net 528 "Net-(U26A-BT_GPIO_3)")
			(pinfunction "1")
			(pintype "passive")
		)
	)
)
